FILE_TYPE = CONNECTIVITY;
{Allegro Design Entry HDL 17.2-2016 S081 (4005846) 1/11/2022}
"PAGE_NUMBER" = 219;
0"NC";
1"P3V3_AUX\g";
2"P3V3_AUX\g";
3"P3V3_AUX\g";
4"P3V3_AUX\g";
5"GND\g";
6"GND\g";
7"GND\g";
8"GND\g";
9"GND\g";
10"SMB_SENSOR_E1S_3V3AUX_SCL"CDS_PHYS_NET_NAME"SMB_SENSOR_E1S_3V3AUX_SCL";
11"SMB_SENSOR_E1S_3V3AUX_SDA"CDS_PHYS_NET_NAME"SMB_SENSOR_E1S_3V3AUX_SDA";
12"SMB_PCIE0_3V3AUX_SCL"CDS_PHYS_NET_NAME"SMB_PCIE0_3V3AUX_SCL";
13"SMB_PCIE0_3V3AUX_SDA"CDS_PHYS_NET_NAME"SMB_PCIE0_3V3AUX_SDA";
14"SMB_INA230_3V3AUX_SCL"CDS_PHYS_NET_NAME"SMB_INA230_3V3AUX_SCL";
15"SMB_INA230_3V3AUX_SDA"CDS_PHYS_NET_NAME"SMB_INA230_3V3AUX_SDA";
16"SMB_FRU_3V3AUX_SCL"CDS_PHYS_NET_NAME"SMB_FRU_3V3AUX_SCL";
17"SMB_FRU_3V3AUX_SDA"CDS_PHYS_NET_NAME"SMB_FRU_3V3AUX_SDA";
18"SMB_BMC_SWB_SCL"CDS_PHYS_NET_NAME"SMB_BMC_SWB_SCL";
19"SMB_INA230_3V3AUX_SCL"CDS_PHYS_NET_NAME"SMB_INA230_3V3AUX_SCL";
20"SMB_PCIE0_3V3AUX_SDA"CDS_PHYS_NET_NAME"SMB_PCIE0_3V3AUX_SDA";
21"SMB_PCIE0_3V3AUX_SCL"CDS_PHYS_NET_NAME"SMB_PCIE0_3V3AUX_SCL";
22"SMB_BMC_SWB_SDA"CDS_PHYS_NET_NAME"SMB_BMC_SWB_SDA";
23"SMB_IOEXP_3V3AUX_SDA"CDS_PHYS_NET_NAME"SMB_IOEXP_3V3AUX_SDA";
24"SMB_IOEXP_3V3AUX_SCL"CDS_PHYS_NET_NAME"SMB_IOEXP_3V3AUX_SCL";
25"SMB_INA230_3V3AUX_SDA"CDS_PHYS_NET_NAME"SMB_INA230_3V3AUX_SDA";
26"SMB_INA230_3V3AUX_SDA_R"CDS_PHYS_NET_NAME"SMB_INA230_3V3AUX_SDA_R";
27"SMB_FRU_3V3AUX_SDA_R"CDS_PHYS_NET_NAME"SMB_FRU_3V3AUX_SDA_R";
28"SMB_FRU_3V3AUX_SCL_R"CDS_PHYS_NET_NAME"SMB_FRU_3V3AUX_SCL_R";
29"SMB_BMC_SWB_SCL_R4"CDS_PHYS_NET_NAME"SMB_BMC_SWB_SCL_R4";
30"SMB_BMC_SWB_SDA_R4"CDS_PHYS_NET_NAME"SMB_BMC_SWB_SDA_R4";
31"SMB_PCIE0_3V3AUX_SDA_R"CDS_PHYS_NET_NAME"SMB_PCIE0_3V3AUX_SDA_R";
32"SMB_INA230_3V3AUX_SCL_R"CDS_PHYS_NET_NAME"SMB_INA230_3V3AUX_SCL_R";
33"SMB_PCIE0_3V3AUX_SCL_R"CDS_PHYS_NET_NAME"SMB_PCIE0_3V3AUX_SCL_R";
34"PCA9548_PCIE3_ADDR0";
35"PCA9548_PCIE3_ADDR1";
36"PCA9548_PCIE3_ADDR2"CDS_PHYS_NET_NAME"PCA9548_PCIE3_ADDR2";
37"PU_RST_SMB_PCIE0_N"CDS_PHYS_NET_NAME"PU_RST_SMB_PCIE0_N";
38"SMB_IOEXP_3V3AUX_SDA_R"CDS_PHYS_NET_NAME"SMB_IOEXP_3V3AUX_SDA_R";
39"SMB_IOEXP_3V3AUX_SCL_R"CDS_PHYS_NET_NAME"SMB_IOEXP_3V3AUX_SCL_R";
40"SMB_PCIE0_3V3AUX_SDA_R3"CDS_PHYS_NET_NAME"SMB_PCIE0_3V3AUX_SDA_R3";
41"SMB_PCIE0_3V3AUX_SCL_R3"CDS_PHYS_NET_NAME"SMB_PCIE0_3V3AUX_SCL_R3";
42"SMB_PCIE0_3V3AUX_SDA_R5"CDS_PHYS_NET_NAME"SMB_PCIE0_3V3AUX_SDA_R5";
43"SMB_PCIE0_3V3AUX_SCL_R5"CDS_PHYS_NET_NAME"SMB_PCIE0_3V3AUX_SCL_R5";
44"SMB_SENSOR_M2_P0_3V3AUX_SCL"CDS_PHYS_NET_NAME"SMB_SENSOR_M2_P0_3V3AUX_SCL";
45"SMB_SENSOR_M2_P0_3V3AUX_SDA"CDS_PHYS_NET_NAME"SMB_SENSOR_M2_P0_3V3AUX_SDA";
46"SMB_FRU_3V3AUX_SDA"CDS_PHYS_NET_NAME"SMB_FRU_3V3AUX_SDA";
47"SMB_FRU_3V3AUX_SCL"CDS_PHYS_NET_NAME"SMB_FRU_3V3AUX_SCL";
48"SMB_BMC_SWB_SCL"CDS_PHYS_NET_NAME"SMB_BMC_SWB_SCL";
49"SMB_BMC_SWB_SDA"CDS_PHYS_NET_NAME"SMB_BMC_SWB_SDA";
50"SMB_SENSOR_M2_P0_3V3AUX_SDA"CDS_PHYS_NET_NAME"SMB_SENSOR_M2_P0_3V3AUX_SDA";
51"SMB_SENSOR_M2_P0_3V3AUX_SCL"CDS_PHYS_NET_NAME"SMB_SENSOR_M2_P0_3V3AUX_SCL";
52"SMB_SENSOR_E1S_3V3AUX_SDA"CDS_PHYS_NET_NAME"SMB_SENSOR_E1S_3V3AUX_SDA";
53"SMB_SENSOR_E1S_3V3AUX_SCL"CDS_PHYS_NET_NAME"SMB_SENSOR_E1S_3V3AUX_SCL";
54"SMB_IOEXP_3V3AUX_SDA"CDS_PHYS_NET_NAME"SMB_IOEXP_3V3AUX_SDA";
55"SMB_IOEXP_3V3AUX_SCL"CDS_PHYS_NET_NAME"SMB_IOEXP_3V3AUX_SCL";
56"RST_SMB_SWITCH_N"CDS_PHYS_NET_NAME"RST_SMB_SWITCH_N";
57"PCA9548_PCIE3_ADDR1";
58"PCA9548_PCIE3_ADDR0";
59"PCA9548_PCIE3_ADDR2";
%"UNIVERSAL_GND"
"1","(-1250,-200)","0","logical_power","I1";
;
HDL_POWER"GND"
ROOM"IO_SLOT"
CDS_LIB"logical_power";
"A"5;
%"Q_RES"
"2","(-700,675)","0","pure_quanta","I10";
;
PART_NUMBER"CS31002FB08"
VALUE"10K"
TOLERANCE"1%"
PACK_TYPE"0402LF"
WATTAGE"1/16W"
MATERIAL"EMPTY"
$LOCATION"R540"
CDS_LIB"pure_quanta"
$LOCATION"R540"
CDS_LOCATION"R540"
$SEC"1"
CDS_SEC"1";
"A"
$PN"1"1;
"B"
$PN"2"58;
%"Q_RES"
"2","(-600,3225)","2","pure_quanta","I18";
;
PART_NUMBER"CS31002FB08"
VALUE"10K"
PACK_TYPE"0402LF"
TOLERANCE"1%"
WATTAGE"1/16W"
MATERIAL"CHIP"
$LOCATION"R1822"
CDS_LIB"pure_quanta"
CDS_LOCATION"R1822"
$SEC"1"
CDS_SEC"1";
"A"
$PN"1"2;
"B"
$PN"2"56;
%"UNIVERSAL_POWER"
"1","(-600,3500)","0","logical_power","I19";
;
HDL_POWER"P3V3_AUX"
CDS_LIB"logical_power";
"A"2;
%"Q_RES"
"2","(-1250,25)","0","pure_quanta","I2";
;
PART_NUMBER"CS21002FB06"
TOLERANCE"1%"
WATTAGE"1/16W"
MATERIAL"CHIP"
PACK_TYPE"0402LF"
VALUE"1K"
$LOCATION"R537"
CDS_LIB"pure_quanta"
$LOCATION"R537"
CDS_LOCATION"R537"
$SEC"1"
CDS_SEC"1";
"A"
$PN"1"59;
"B"
$PN"2"5;
%"Q_RES"
"1","(3875,-1275)","0","pure_quanta","I20";
;
PART_NUMBER"CS22202JB07"
MATERIAL"CHIP"
VALUE"2.2K"
TOLERANCE"5%"
$LOCATION"R1090"
WATTAGE"1/16W"
PACK_TYPE"0402LF"
CDS_LIB"pure_quanta"
CDS_LOCATION"R1090"
$SEC"1"
CDS_SEC"1";
"B"
$PN"2"45;
"A"
$PN"1"4;
%"Q_RES"
"1","(3875,-1225)","0","pure_quanta","I21";
;
PART_NUMBER"CS22202JB07"
WATTAGE"1/16W"
VALUE"2.2K"
TOLERANCE"5%"
MATERIAL"CHIP"
PACK_TYPE"0402LF"
$LOCATION"R1089"
CDS_LIB"pure_quanta"
CDS_LOCATION"R1089"
$SEC"1"
CDS_SEC"1";
"B"
$PN"2"44;
"A"
$PN"1"4;
%"Q_RES"
"1","(3875,-900)","0","pure_quanta","I22";
;
PART_NUMBER"CS22202JB07"
PACK_TYPE"0402LF"
VALUE"2.2K"
TOLERANCE"5%"
WATTAGE"1/16W"
MATERIAL"CHIP"
$LOCATION"R651"
CDS_LIB"pure_quanta"
CDS_LOCATION"R651"
$SEC"1"
CDS_SEC"1";
"B"
$PN"2"47;
"A"
$PN"1"4;
%"Q_RES"
"1","(3875,-950)","0","pure_quanta","I23";
;
PART_NUMBER"CS22202JB07"
TOLERANCE"5%"
VALUE"2.2K"
MATERIAL"CHIP"
$LOCATION"R652"
CDS_LIB"pure_quanta"
PACK_TYPE"0402LF"
WATTAGE"1/16W"
CDS_LOCATION"R652"
$SEC"1"
CDS_SEC"1";
"B"
$PN"2"46;
"A"
$PN"1"4;
%"Q_RES"
"1","(3875,-625)","0","pure_quanta","I24";
;
PART_NUMBER"CS31002FB08"
VALUE"10K"
MATERIAL"CHIP"
TOLERANCE"1%"
$LOCATION"R2985"
CDS_LIB"pure_quanta"
PACK_TYPE"0402LF"
WATTAGE"1/16W"
CDS_LOCATION"R2985"
$SEC"1"
CDS_SEC"1";
"B"
$PN"2"49;
"A"
$PN"1"4;
%"Q_RES"
"1","(3875,-575)","0","pure_quanta","I25";
;
PART_NUMBER"CS31002FB08"
WATTAGE"1/16W"
PACK_TYPE"0402LF"
MATERIAL"CHIP"
VALUE"10K"
TOLERANCE"1%"
$LOCATION"R2984"
CDS_LIB"pure_quanta"
CDS_LOCATION"R2984"
$SEC"1"
CDS_SEC"1";
"B"
$PN"2"48;
"A"
$PN"1"4;
%"Q_RES"
"2","(-1250,675)","0","pure_quanta","I3";
;
PART_NUMBER"CS31002FB08"
WATTAGE"1/16W"
VALUE"10K"
PACK_TYPE"0402LF"
TOLERANCE"1%"
MATERIAL"EMPTY"
$LOCATION"R536"
CDS_LIB"pure_quanta"
$LOCATION"R536"
CDS_LOCATION"R536"
$SEC"1"
CDS_SEC"1";
"A"
$PN"1"1;
"B"
$PN"2"59;
%"Q_RES"
"1","(600,2425)","2","pure_quanta","I35";
;
PART_NUMBER"CS00002JB13"
MATERIAL"CHIP"
TOLERANCE"5%"
VALUE"0"
$LOCATION"R3526"
CDS_LIB"pure_quanta"
WATTAGE"1/16W"
PACK_TYPE"0402LF"
CDS_LOCATION"R3526"
$SEC"1"
CDS_SEC"1";
"B"
$PN"2"53;
"A"
$PN"1"43;
%"Q_RES"
"1","(600,2525)","2","pure_quanta","I36";
;
PART_NUMBER"CS00002JB13"
VALUE"0"
TOLERANCE"5%"
MATERIAL"CHIP"
$LOCATION"R2967"
CDS_LIB"pure_quanta"
WATTAGE"1/16W"
PACK_TYPE"0402LF"
CDS_LOCATION"R2967"
$SEC"1"
CDS_SEC"1";
"B"
$PN"2"51;
"A"
$PN"1"41;
%"Q_RES"
"1","(600,2475)","2","pure_quanta","I37";
;
PART_NUMBER"CS00002JB13"
TOLERANCE"5%"
VALUE"0"
MATERIAL"CHIP"
$LOCATION"R3527"
WATTAGE"1/16W"
PACK_TYPE"0402LF"
CDS_LIB"pure_quanta"
CDS_LOCATION"R3527"
$SEC"1"
CDS_SEC"1";
"B"
$PN"2"52;
"A"
$PN"1"42;
%"Q_RES"
"1","(600,2625)","2","pure_quanta","I38";
;
PART_NUMBER"CS00002JB13"
TOLERANCE"5%"
MATERIAL"CHIP"
VALUE"0"
$LOCATION"R3393"
CDS_LIB"pure_quanta"
WATTAGE"1/16W"
SEC_TYPE"0402LF"
PACK_TYPE"0402LF"
CDS_LOCATION"R3393"
SEC"1";
"B"
$PN"2"55;
"A"
$PN"1"39;
%"Q_RES"
"1","(600,2575)","2","pure_quanta","I39";
;
PART_NUMBER"CS00002JB13"
MATERIAL"CHIP"
VALUE"0"
TOLERANCE"5%"
$LOCATION"R2968"
CDS_LIB"pure_quanta"
PACK_TYPE"0402LF"
WATTAGE"1/16W"
CDS_LOCATION"R2968"
$SEC"1"
CDS_SEC"1";
"B"
$PN"2"50;
"A"
$PN"1"40;
%"UNIVERSAL_POWER"
"1","(-1250,1050)","0","logical_power","I4";
;
HDL_POWER"P3V3_AUX"
CDS_LIB"logical_power";
"A"1;
%"Q_RES"
"1","(600,2675)","2","pure_quanta","I40";
;
PART_NUMBER"CS00002JB13"
VALUE"0"
TOLERANCE"5%"
MATERIAL"CHIP"
$LOCATION"R3394"
WATTAGE"1/16W"
PACK_TYPE"0402LF"
CDS_LIB"pure_quanta"
CDS_LOCATION"R3394"
$SEC"1"
CDS_SEC"1";
"B"
$PN"2"54;
"A"
$PN"1"38;
%"Q_RES"
"1","(500,2875)","0","pure_quanta","I41";
;
PART_NUMBER"CS00002JB13"
TOLERANCE"5%"
VALUE"0"
MATERIAL"CHIP"
$LOCATION"R2268"
CDS_LIB"pure_quanta"
WATTAGE"1/16W"
PACK_TYPE"0402LF"
CDS_LOCATION"R2268"
$SEC"1"
CDS_SEC"1";
"B"
$PN"2"37;
"A"
$PN"1"56;
%"TCA9548APWR"
"1","(2075,2750)","0","pure_quanta","I45";
;
PART_NUMBER"AL009548K02"
PART_TYPE"SMLF"
MATERIAL"IC"
VALUE"TCA9548APWR"
LOCATION"U36"
CDS_LIB"pure_quanta"
CDS_LMAN_SYM_OUTLINE"-200,475,200,-475"
SEC_TYPE""
NEEDS_NO_SIZE"TRUE"
SEC"1";
"SD4"
$PN"13"30;
"SC4"
$PN"14"29;
"SD5"
$PN"15"27;
"SC5"
$PN"16"28;
"SD6"
$PN"17"26;
"SC6"
$PN"18"32;
"SD7"
$PN"19"0;
"SC7"
$PN"20"0;
"A2"
$PN"21"36;
"SCL"
$PN"22"33;
"SDA"
$PN"23"31;
"VCC"
$PN"24"3;
"GND"
$PN"12"9;
"SC3"
$PN"11"43;
"SD3"
$PN"10"42;
"SC2"
$PN"9"41;
"SD2"
$PN"8"40;
"SC1"
$PN"7"39;
"SD1"
$PN"6"38;
"SC0"
$PN"5"0;
"SD0"
$PN"4"0;
"RESET# \B"
$PN"3"37;
"A1"
$PN"2"35;
"A0"
$PN"1"34;
%"UNIVERSAL_GND"
"1","(1200,3275)","0","logical_power","I46";
;
HDL_POWER"GND"
CDS_LIB"logical_power";
"A"8;
%"Q_CAP"
"1","(1200,3500)","0","pure_quanta","I47";
;
PART_NUMBER"CH4104K1B00"
PACK_TYPE"0402"
VOLTAGE"25V"
MATERIAL"X7R"
TOLERANCE"10%"
VALUE"0.1UF"
$LOCATION"C174"
CDS_LIB"pure_quanta"
$LOCATION"C174"
CDS_LOCATION"C174"
$SEC"1"
CDS_SEC"1";
"B"
$PN"2"8;
"A"
$PN"1"3;
%"UNIVERSAL_POWER"
"1","(1200,3825)","0","logical_power","I48";
;
HDL_POWER"P3V3_AUX"
CDS_LIB"logical_power";
"A"3;
%"Q_RES"
"1","(3875,75)","0","pure_quanta","I49";
;
PART_NUMBER"CS22202JB07"
MATERIAL"CHIP"
TOLERANCE"5%"
PACK_TYPE"0402LF"
VALUE"2.2K"
WATTAGE"1/16W"
$LOCATION"R3535"
CDS_LIB"pure_quanta"
CDS_LOCATION"R3535"
$SEC"1"
CDS_SEC"1";
"B"
$PN"2"10;
"A"
$PN"1"4;
%"UNIVERSAL_GND"
"1","(-975,-200)","0","logical_power","I5";
;
HDL_POWER"GND"
ROOM"IO_SLOT"
CDS_LIB"logical_power";
"A"6;
%"Q_RES"
"1","(3875,25)","0","pure_quanta","I50";
;
PART_NUMBER"CS22202JB07"
MATERIAL"CHIP"
TOLERANCE"5%"
VALUE"2.2K"
$LOCATION"R3536"
CDS_LIB"pure_quanta"
PACK_TYPE"0402LF"
WATTAGE"1/16W"
CDS_LOCATION"R3536"
$SEC"1"
CDS_SEC"1";
"B"
$PN"2"11;
"A"
$PN"1"4;
%"Q_RES"
"1","(3850,325)","0","pure_quanta","I51";
;
PART_NUMBER"CS22202JB07"
TOLERANCE"5%"
VALUE"2.2K"
MATERIAL"CHIP"
$LOCATION"R3583"
CDS_LIB"pure_quanta"
PACK_TYPE"0402LF"
WATTAGE"1/16W"
CDS_LOCATION"R3583"
$SEC"1"
CDS_SEC"1";
"B"
$PN"2"23;
"A"
$PN"1"4;
%"Q_RES"
"1","(3850,375)","0","pure_quanta","I52";
;
PART_NUMBER"CS22202JB07"
TOLERANCE"5%"
VALUE"2.2K"
WATTAGE"1/16W"
MATERIAL"CHIP"
PACK_TYPE"0402LF"
$LOCATION"R3582"
CDS_LIB"pure_quanta"
CDS_LOCATION"R3582"
$SEC"1"
CDS_SEC"1";
"B"
$PN"2"24;
"A"
$PN"1"4;
%"Q_RES"
"1","(3850,600)","0","pure_quanta","I53";
;
PART_NUMBER"CS22202JB07"
TOLERANCE"5%"
VALUE"2.2K"
MATERIAL"CHIP"
$LOCATION"R3396"
WATTAGE"1/16W"
PACK_TYPE"0402LF"
CDS_LIB"pure_quanta"
CDS_LOCATION"R3396"
$SEC"1"
CDS_SEC"1";
"B"
$PN"2"25;
"A"
$PN"1"4;
%"Q_RES"
"1","(3850,650)","0","pure_quanta","I54";
;
PART_NUMBER"CS22202JB07"
VALUE"2.2K"
PACK_TYPE"0402LF"
MATERIAL"CHIP"
TOLERANCE"5%"
WATTAGE"1/16W"
$LOCATION"R3395"
CDS_LIB"pure_quanta"
CDS_LOCATION"R3395"
$SEC"1"
CDS_SEC"1";
"B"
$PN"2"14;
"A"
$PN"1"4;
%"UNIVERSAL_POWER"
"1","(3425,1225)","0","logical_power","I55";
;
HDL_POWER"P3V3_AUX"
CDS_LIB"logical_power";
"A"4;
%"Q_RES"
"1","(3850,975)","0","pure_quanta","I56";
;
PART_NUMBER"CS22202JB07"
TOLERANCE"5%"
VALUE"2.2K"
MATERIAL"EMPTY"
$LOCATION"R2205"
CDS_LIB"pure_quanta"
PACK_TYPE"0402LF"
WATTAGE"1/16W"
CDS_LOCATION"R2205"
$SEC"1"
CDS_SEC"1";
"B"
$PN"2"13;
"A"
$PN"1"4;
%"Q_RES"
"1","(3850,1025)","0","pure_quanta","I57";
;
PART_NUMBER"CS22202JB07"
WATTAGE"1/16W"
PACK_TYPE"0402LF"
TOLERANCE"5%"
VALUE"2.2K"
MATERIAL"EMPTY"
$LOCATION"R2204"
CDS_LIB"pure_quanta"
CDS_LOCATION"R2204"
$SEC"1"
CDS_SEC"1";
"B"
$PN"2"12;
"A"
$PN"1"4;
%"UNIVERSAL_GND"
"1","(2575,2150)","0","logical_power","I58";
;
HDL_POWER"GND"
CDS_LIB"logical_power";
"A"9;
%"Q_RES"
"1","(3400,2525)","0","pure_quanta","I59";
;
PART_NUMBER"CS00002JB13"
MATERIAL"CHIP"
TOLERANCE"5%"
VALUE"0"
$LOCATION"R3580"
CDS_LIB"pure_quanta"
WATTAGE"1/16W"
PACK_TYPE"0402LF"
CDS_LOCATION"R3580"
$SEC"1"
CDS_SEC"1";
"B"
$PN"2"19;
"A"
$PN"1"32;
%"Q_RES"
"2","(-975,25)","0","pure_quanta","I6";
;
PART_NUMBER"CS21002FB06"
TOLERANCE"1%"
WATTAGE"1/16W"
MATERIAL"CHIP"
VALUE"1K"
PACK_TYPE"0402LF"
$LOCATION"R539"
CDS_LIB"pure_quanta"
$LOCATION"R539"
CDS_LOCATION"R539"
$SEC"1"
CDS_SEC"1";
"A"
$PN"1"57;
"B"
$PN"2"6;
%"Q_RES"
"1","(3400,2575)","0","pure_quanta","I60";
;
PART_NUMBER"CS00002JB13"
MATERIAL"CHIP"
VALUE"0"
TOLERANCE"5%"
$LOCATION"R3581"
WATTAGE"1/16W"
PACK_TYPE"0402LF"
CDS_LIB"pure_quanta"
CDS_LOCATION"R3581"
$SEC"1"
CDS_SEC"1";
"B"
$PN"2"15;
"A"
$PN"1"26;
%"Q_RES"
"1","(3400,2625)","0","pure_quanta","I61";
;
PART_NUMBER"CS00002JB13"
VALUE"0"
MATERIAL"CHIP"
TOLERANCE"5%"
$LOCATION"R2565"
PACK_TYPE"0402LF"
WATTAGE"1/16W"
CDS_LIB"pure_quanta"
CDS_LOCATION"R2565"
$SEC"1"
CDS_SEC"1";
"B"
$PN"2"16;
"A"
$PN"1"28;
%"Q_RES"
"1","(3400,2675)","0","pure_quanta","I62";
;
PART_NUMBER"CS00002JB13"
VALUE"0"
MATERIAL"CHIP"
TOLERANCE"5%"
$LOCATION"R2566"
CDS_LIB"pure_quanta"
PACK_TYPE"0402LF"
WATTAGE"1/16W"
CDS_LOCATION"R2566"
$SEC"1"
CDS_SEC"1";
"B"
$PN"2"17;
"A"
$PN"1"27;
%"Q_RES"
"1","(3400,2725)","0","pure_quanta","I63";
;
PART_NUMBER"CS00002JB13"
VALUE"0"
MATERIAL"CHIP"
TOLERANCE"5%"
$LOCATION"R2703"
PACK_TYPE"0402LF"
WATTAGE"1/16W"
CDS_LIB"pure_quanta"
CDS_LOCATION"R2703"
$SEC"1"
CDS_SEC"1";
"B"
$PN"2"18;
"A"
$PN"1"29;
%"Q_RES"
"1","(3400,2775)","0","pure_quanta","I64";
;
PART_NUMBER"CS00002JB13"
VALUE"0"
TOLERANCE"5%"
MATERIAL"CHIP"
$LOCATION"R2704"
CDS_LIB"pure_quanta"
PACK_TYPE"0402LF"
WATTAGE"1/16W"
CDS_LOCATION"R2704"
$SEC"1"
CDS_SEC"1";
"B"
$PN"2"22;
"A"
$PN"1"30;
%"Q_RES"
"1","(3475,2975)","2","pure_quanta","I65";
;
PART_NUMBER"CS03322FB03"
VALUE"33.2"
WATTAGE"1/16W"
PACK_TYPE"0402LF"
TOLERANCE"1%"
MATERIAL"CHIP"
$LOCATION"R588"
CDS_LIB"pure_quanta"
$LOCATION"R588"
CDS_LOCATION"R588"
$SEC"1"
CDS_SEC"1";
"B"
$PN"2"33;
"A"
$PN"1"21;
%"Q_RES"
"1","(3475,3025)","2","pure_quanta","I66";
;
PART_NUMBER"CS03322FB03"
TOLERANCE"1%"
MATERIAL"CHIP"
VALUE"33.2"
$LOCATION"R589"
WATTAGE"1/16W"
CDS_LIB"pure_quanta"
PACK_TYPE"0402LF"
$LOCATION"R589"
CDS_LOCATION"R589"
$SEC"1"
CDS_SEC"1";
"B"
$PN"2"31;
"A"
$PN"1"20;
%"UNIVERSAL_GND"
"1","(-700,-200)","0","logical_power","I7";
;
HDL_POWER"GND"
ROOM"IO_SLOT"
CDS_LIB"logical_power";
"A"7;
%"Q_RES"
"2","(-700,25)","0","pure_quanta","I8";
;
PART_NUMBER"CS21002FB06"
TOLERANCE"1%"
PACK_TYPE"0402LF"
VALUE"1K"
MATERIAL"CHIP"
WATTAGE"1/16W"
$LOCATION"R587"
CDS_LIB"pure_quanta"
$LOCATION"R587"
CDS_LOCATION"R587"
$SEC"1"
CDS_SEC"1";
"A"
$PN"1"58;
"B"
$PN"2"7;
%"Q_RES"
"2","(-975,675)","0","pure_quanta","I9";
;
PART_NUMBER"CS31002FB08"
VALUE"10K"
WATTAGE"1/16W"
TOLERANCE"1%"
MATERIAL"EMPTY"
PACK_TYPE"0402LF"
$LOCATION"R538"
CDS_LIB"pure_quanta"
$LOCATION"R538"
CDS_LOCATION"R538"
$SEC"1"
CDS_SEC"1";
"A"
$PN"1"1;
"B"
$PN"2"57;
END.
